G04*
G04 #@! TF.GenerationSoftware,Altium Limited,Altium Designer,23.0.1 (38)*
G04*
G04 Layer_Color=32896*
%FSLAX25Y25*%
%MOIN*%
G70*
G04*
G04 #@! TF.SameCoordinates,C48E81DB-6E20-4E2D-80E6-7C5AFAA1A21F*
G04*
G04*
G04 #@! TF.FilePolarity,Positive*
G04*
G01*
G75*
M02*
